# T6G (Grand Teton) — schematic netlist excerpt (pin names and nets, part order shuffled) for the footprints in the layout excerpt that follows; sources: Cadence DE-HDL packaged netlist, KiCad conversion of 04192023_DAF0TMB3IC0_F0TG_MB_C_brd_V02_OCP.brd

R6120  Q_RES  1K 1% CHIP  pkg 0402LF  page 84 : A = PVDD18_S5_P0 ; B = FM_BOARD_SKU_ID4
R3086  Q_RES  130 1% CHIP  pkg 0402LF  page 255 : A = LED_PWRGD_PVDD33_S5_R ; B = P3V3_AUX

(kicad_pcb
	(version 20260206)
	(generator "pcbnew")
	(generator_version "10.0")
	(general
		(thickness 1.6)
		(legacy_teardrops no)
	)
	(paper "A4")
	(title_block
		(title "04192023_DAF0TMB3IC0_F0TG_MB_C_brd_V02_OCP.brd")
		(comment 1 "Grand Teton / footprints 5303-5304 of 8354")
	)
	(layers
		(0 "F.Cu" signal "TOP")
		(4 "In1.Cu" signal "GND")
		(6 "In2.Cu" signal "IN1")
		(8 "In3.Cu" signal "GND1")
		(10 "In4.Cu" signal "IN2")
		(12 "In5.Cu" signal "GND2")
		(14 "In6.Cu" signal "IN3")
		(16 "In7.Cu" signal "GND3")
		(18 "In8.Cu" signal "VCC")
		(20 "In9.Cu" signal "VCC1")
		(22 "In10.Cu" signal "GND4")
		(24 "In11.Cu" signal "IN4")
		(26 "In12.Cu" signal "GND5")
		(28 "In13.Cu" signal "IN5")
		(30 "In14.Cu" signal "GND6")
		(32 "In15.Cu" signal "IN6")
		(34 "In16.Cu" signal "GND7")
		(2 "B.Cu" signal "BOTTOM")
		(9 "F.Adhes" user "F.Adhesive")
		(11 "B.Adhes" user "B.Adhesive")
		(13 "F.Paste" user "Package Geometry/Pastemask Top")
		(15 "B.Paste" user "Package Geometry/Pastemask Bottom")
		(5 "F.SilkS" user "Ref Des/Silkscreen Top")
		(7 "B.SilkS" user "Ref Des/Silkscreen Bottom")
		(1 "F.Mask" user "Board Geometry/Soldermask Top")
		(3 "B.Mask" user "Board Geometry/Soldermask Bottom")
		(17 "Dwgs.User" user "User.Drawings")
		(19 "Cmts.User" user "User.Comments")
		(21 "Eco1.User" user "User.Eco1")
		(23 "Eco2.User" user "User.Eco2")
		(25 "Edge.Cuts" user "Board Geometry/Outline")
		(27 "Margin" user)
		(31 "F.CrtYd" user "Package Geometry/Place Bound Top")
		(29 "B.CrtYd" user "Package Geometry/Place Bound Bottom")
		(35 "F.Fab" user "Ref Des/Assembly Top")
		(33 "B.Fab" user "Ref Des/Assembly Bottom")
	)
	(footprint ""
		(layer "B.Cu")
		(at 322.603876 -66.708782 90)
		(property "Reference" "R3086"
			(at 0 0 90)
			(layer "B.SilkS")
			(hide yes)
			(effects
				(font
					(size 1.27 1.27)
				)
				(justify mirror)
			)
		)
		(property "Value" ""
			(at 0 0 90)
			(layer "B.Fab")
			(effects
				(font
					(size 1.27 1.27)
				)
				(justify mirror)
			)
		)
		(duplicate_pad_numbers_are_jumpers no)
		(fp_line
			(start 0.7874 -0.4064)
			(end -0.7874 -0.4064)
			(stroke
				(width 0.1524)
				(type default)
			)
			(layer "B.SilkS")
		)
		(fp_line
			(start -0.7874 -0.4064)
			(end -0.7874 0.4064)
			(stroke
				(width 0.1524)
				(type default)
			)
			(layer "B.SilkS")
		)
		(fp_line
			(start 0.7874 0.4064)
			(end 0.7874 -0.4064)
			(stroke
				(width 0.1524)
				(type default)
			)
			(layer "B.SilkS")
		)
		(fp_line
			(start -0.7874 0.4064)
			(end 0.7874 0.4064)
			(stroke
				(width 0.1524)
				(type default)
			)
			(layer "B.SilkS")
		)
		(fp_line
			(start 0.67945 -0.305054)
			(end 0.12065 -0.305054)
			(stroke
				(width 0.1)
				(type default)
			)
			(layer "B.Fab")
		)
		(fp_line
			(start 0.12065 -0.305054)
			(end 0.12065 -0.2794)
			(stroke
				(width 0.1)
				(type default)
			)
			(layer "B.Fab")
		)
		(fp_line
			(start -0.12065 -0.3048)
			(end -0.67945 -0.3048)
			(stroke
				(width 0.1)
				(type default)
			)
			(layer "B.Fab")
		)
		(fp_line
			(start -0.67945 -0.3048)
			(end -0.67945 0.3048)
			(stroke
				(width 0.1)
				(type default)
			)
			(layer "B.Fab")
		)
		(fp_line
			(start 0.12065 -0.2794)
			(end -0.12065 -0.2794)
			(stroke
				(width 0.1)
				(type default)
			)
			(layer "B.Fab")
		)
		(fp_line
			(start -0.12065 -0.2794)
			(end -0.12065 -0.3048)
			(stroke
				(width 0.1)
				(type default)
			)
			(layer "B.Fab")
		)
		(fp_line
			(start 0.12065 0.2794)
			(end 0.12065 0.3048)
			(stroke
				(width 0.1)
				(type default)
			)
			(layer "B.Fab")
		)
		(fp_line
			(start -0.120396 0.2794)
			(end 0.12065 0.2794)
			(stroke
				(width 0.1)
				(type default)
			)
			(layer "B.Fab")
		)
		(fp_line
			(start 0.67945 0.3048)
			(end 0.67945 -0.305054)
			(stroke
				(width 0.1)
				(type default)
			)
			(layer "B.Fab")
		)
		(fp_line
			(start 0.12065 0.3048)
			(end 0.67945 0.3048)
			(stroke
				(width 0.1)
				(type default)
			)
			(layer "B.Fab")
		)
		(fp_line
			(start -0.120396 0.3048)
			(end -0.120396 0.2794)
			(stroke
				(width 0.1)
				(type default)
			)
			(layer "B.Fab")
		)
		(fp_line
			(start -0.67945 0.3048)
			(end -0.120396 0.3048)
			(stroke
				(width 0.1)
				(type default)
			)
			(layer "B.Fab")
		)
		(pad "1" smd circle
			(at 0.40005 0 270)
			(size 0 0)
			(layers "B.Cu" "B.Mask" "B.Paste")
			(net "LED_PWRGD_PVDD33_S5_R")
		)
		(pad "2" smd circle
			(at -0.40005 0 270)
			(size 0 0)
			(layers "B.Cu" "B.Mask" "B.Paste")
			(net "P3V3_AUX")
		)
	)
	(footprint ""
		(layer "B.Cu")
		(at 406.312878 -349.209614 -90)
		(property "Reference" "R6120"
			(at 0 0 90)
			(layer "B.SilkS")
			(hide yes)
			(effects
				(font
					(size 1.27 1.27)
				)
				(justify mirror)
			)
		)
		(property "Value" ""
			(at 0 0 90)
			(layer "B.Fab")
			(effects
				(font
					(size 1.27 1.27)
				)
				(justify mirror)
			)
		)
		(duplicate_pad_numbers_are_jumpers no)
		(fp_line
			(start -0.7874 0.4064)
			(end 0.7874 0.4064)
			(stroke
				(width 0.1524)
				(type default)
			)
			(layer "B.SilkS")
		)
		(fp_line
			(start 0.7874 0.4064)
			(end 0.7874 -0.4064)
			(stroke
				(width 0.1524)
				(type default)
			)
			(layer "B.SilkS")
		)
		(fp_line
			(start -0.7874 -0.4064)
			(end -0.7874 0.4064)
			(stroke
				(width 0.1524)
				(type default)
			)
			(layer "B.SilkS")
		)
		(fp_line
			(start 0.7874 -0.4064)
			(end -0.7874 -0.4064)
			(stroke
				(width 0.1524)
				(type default)
			)
			(layer "B.SilkS")
		)
		(fp_line
			(start -0.67945 0.3048)
			(end -0.120396 0.3048)
			(stroke
				(width 0.1)
				(type default)
			)
			(layer "B.Fab")
		)
		(fp_line
			(start -0.120396 0.3048)
			(end -0.120396 0.2794)
			(stroke
				(width 0.1)
				(type default)
			)
			(layer "B.Fab")
		)
		(fp_line
			(start 0.12065 0.3048)
			(end 0.67945 0.3048)
			(stroke
				(width 0.1)
				(type default)
			)
			(layer "B.Fab")
		)
		(fp_line
			(start 0.67945 0.3048)
			(end 0.67945 -0.305054)
			(stroke
				(width 0.1)
				(type default)
			)
			(layer "B.Fab")
		)
		(fp_line
			(start -0.120396 0.2794)
			(end 0.12065 0.2794)
			(stroke
				(width 0.1)
				(type default)
			)
			(layer "B.Fab")
		)
		(fp_line
			(start 0.12065 0.2794)
			(end 0.12065 0.3048)
			(stroke
				(width 0.1)
				(type default)
			)
			(layer "B.Fab")
		)
		(fp_line
			(start -0.12065 -0.2794)
			(end -0.12065 -0.3048)
			(stroke
				(width 0.1)
				(type default)
			)
			(layer "B.Fab")
		)
		(fp_line
			(start 0.12065 -0.2794)
			(end -0.12065 -0.2794)
			(stroke
				(width 0.1)
				(type default)
			)
			(layer "B.Fab")
		)
		(fp_line
			(start -0.67945 -0.3048)
			(end -0.67945 0.3048)
			(stroke
				(width 0.1)
				(type default)
			)
			(layer "B.Fab")
		)
		(fp_line
			(start -0.12065 -0.3048)
			(end -0.67945 -0.3048)
			(stroke
				(width 0.1)
				(type default)
			)
			(layer "B.Fab")
		)
		(fp_line
			(start 0.12065 -0.305054)
			(end 0.12065 -0.2794)
			(stroke
				(width 0.1)
				(type default)
			)
			(layer "B.Fab")
		)
		(fp_line
			(start 0.67945 -0.305054)
			(end 0.12065 -0.305054)
			(stroke
				(width 0.1)
				(type default)
			)
			(layer "B.Fab")
		)
		(pad "1" smd circle
			(at 0.40005 0 90)
			(size 0 0)
			(layers "B.Cu" "B.Mask" "B.Paste")
			(net "PVDD18_S5_P0")
		)
		(pad "2" smd circle
			(at -0.40005 0 90)
			(size 0 0)
			(layers "B.Cu" "B.Mask" "B.Paste")
			(net "FM_BOARD_SKU_ID4")
		)
	)
)
